(kicad_pcb
	(version 20260206)
	(generator "pcbnew")
	(generator_version "10.0")
	(general
		(thickness 1.6)
		(legacy_teardrops no)
	)
	(paper "A4")
	(title_block
		(title "04192023_DAF0TMB3IC0_F0TG_MB_C_brd_V02_OCP.brd")
		(comment 1 "Grand Teton / footprints 4452-4458 of 8354")
	)
	(layers
		(0 "F.Cu" signal "TOP")
		(4 "In1.Cu" signal "GND")
		(6 "In2.Cu" signal "IN1")
		(8 "In3.Cu" signal "GND1")
		(10 "In4.Cu" signal "IN2")
		(12 "In5.Cu" signal "GND2")
		(14 "In6.Cu" signal "IN3")
		(16 "In7.Cu" signal "GND3")
		(18 "In8.Cu" signal "VCC")
		(20 "In9.Cu" signal "VCC1")
		(22 "In10.Cu" signal "GND4")
		(24 "In11.Cu" signal "IN4")
		(26 "In12.Cu" signal "GND5")
		(28 "In13.Cu" signal "IN5")
		(30 "In14.Cu" signal "GND6")
		(32 "In15.Cu" signal "IN6")
		(34 "In16.Cu" signal "GND7")
		(2 "B.Cu" signal "BOTTOM")
		(9 "F.Adhes" user "F.Adhesive")
		(11 "B.Adhes" user "B.Adhesive")
		(13 "F.Paste" user "Package Geometry/Pastemask Top")
		(15 "B.Paste" user "Package Geometry/Pastemask Bottom")
		(5 "F.SilkS" user "Ref Des/Silkscreen Top")
		(7 "B.SilkS" user "Ref Des/Silkscreen Bottom")
		(1 "F.Mask" user "Board Geometry/Soldermask Top")
		(3 "B.Mask" user "Board Geometry/Soldermask Bottom")
		(17 "Dwgs.User" user "User.Drawings")
		(19 "Cmts.User" user "User.Comments")
		(21 "Eco1.User" user "User.Eco1")
		(23 "Eco2.User" user "User.Eco2")
		(25 "Edge.Cuts" user "Board Geometry/Outline")
		(27 "Margin" user)
		(31 "F.CrtYd" user "Package Geometry/Place Bound Top")
		(29 "B.CrtYd" user "Package Geometry/Place Bound Bottom")
		(35 "F.Fab" user "Ref Des/Assembly Top")
		(33 "B.Fab" user "Ref Des/Assembly Bottom")
	)
	(footprint ""
		(layer "F.Cu")
		(at 241.656108 -385.27736 90)
		(property "Reference" "PPQ1"
			(at -1.930908 -3.4417 90)
			(unlocked yes)
			(layer "F.SilkS")
			(effects
				(font
					(size 0.7874 0.5842)
					(thickness 0.1524)
				)
				(justify left)
			)
		)
		(property "Value" ""
			(at 0 0 90)
			(layer "F.Fab")
			(effects
				(font
					(size 1.27 1.27)
				)
			)
		)
		(duplicate_pad_numbers_are_jumpers no)
		(fp_line
			(start 2.350008 -2.649982)
			(end 2.350008 -2.4892)
			(stroke
				(width 0.1524)
				(type default)
			)
			(layer "F.SilkS")
		)
		(fp_line
			(start -2.350008 -2.649982)
			(end 2.350008 -2.649982)
			(stroke
				(width 0.1524)
				(type default)
			)
			(layer "F.SilkS")
		)
		(fp_line
			(start -2.350008 -2.4384)
			(end -2.350008 -2.649982)
			(stroke
				(width 0.1524)
				(type default)
			)
			(layer "F.SilkS")
		)
		(fp_line
			(start 2.350008 2.4892)
			(end 2.350008 2.649982)
			(stroke
				(width 0.1524)
				(type default)
			)
			(layer "F.SilkS")
		)
		(fp_line
			(start 2.350008 2.649982)
			(end -2.350008 2.649982)
			(stroke
				(width 0.1524)
				(type default)
			)
			(layer "F.SilkS")
		)
		(fp_line
			(start -2.350008 2.649982)
			(end -2.350008 2.413)
			(stroke
				(width 0.1524)
				(type default)
			)
			(layer "F.SilkS")
		)
		(fp_poly
			(pts
				(xy -3.28803 -4.262628) (xy -2.492502 -4.177538) (xy -3.02006 -3.186684)
			)
			(stroke
				(width 0)
				(type default)
			)
			(fill yes)
			(layer "F.SilkS")
		)
		(fp_line
			(start 2.350008 -2.649982)
			(end 2.350008 2.649982)
			(stroke
				(width 0.1)
				(type default)
			)
			(layer "F.Fab")
		)
		(fp_line
			(start -2.350008 -2.649982)
			(end 2.350008 -2.649982)
			(stroke
				(width 0.1)
				(type default)
			)
			(layer "F.Fab")
		)
		(fp_line
			(start 2.350008 2.649982)
			(end -2.350008 2.649982)
			(stroke
				(width 0.1)
				(type default)
			)
			(layer "F.Fab")
		)
		(fp_line
			(start -2.350008 2.649982)
			(end -2.350008 -2.649982)
			(stroke
				(width 0.1)
				(type default)
			)
			(layer "F.Fab")
		)
		(fp_poly
			(pts
				(xy -3.717544 -1.905) (xy -4.758944 -2.3241) (xy -4.758944 -1.524)
			)
			(stroke
				(width 0)
				(type default)
			)
			(fill yes)
			(layer "F.Fab")
		)
		(pad "1" smd rect
			(at -2.999994 -1.905)
			(size 0.7112 1.1684)
			(layers "F.Cu" "F.Mask" "F.Paste")
			(net "P12V_AUX")
		)
		(pad "2" smd rect
			(at -2.999994 -0.635)
			(size 0.7112 1.1684)
			(layers "F.Cu" "F.Mask" "F.Paste")
			(net "P12V_AUX")
		)
		(pad "3" smd rect
			(at -2.999994 0.635)
			(size 0.7112 1.1684)
			(layers "F.Cu" "F.Mask" "F.Paste")
			(net "P12V_AUX")
		)
		(pad "4" smd rect
			(at -2.999994 1.905)
			(size 0.7112 1.1684)
			(layers "F.Cu" "F.Mask" "F.Paste")
			(net "P12V_HSC_GATE_G5")
		)
		(pad "5" smd circle
			(at 0.925068 0)
			(size 0 0)
			(layers "F.Cu" "F.Mask" "F.Paste")
			(net "P12V_MAIN_R")
		)
		(zone
			(layer "F.Cu")
			(hatch none 0.5)
			(connect_pads
				(clearance 0)
			)
			(min_thickness 0.25)
			(keepout
				(tracks not_allowed)
				(vias allowed)
				(pads allowed)
				(copperpour not_allowed)
				(footprints allowed)
			)
			(placement
				(enabled no)
				(sheetname "")
			)
			(fill
				(thermal_gap 0.5)
				(thermal_bridge_width 0.5)
				(island_removal_mode 0)
			)
			(polygon
				(pts
					(xy 239.014508 -383.7178) (xy 244.297708 -383.7178) (xy 244.297708 -382.92786) (xy 239.014508 -382.92786)
				)
			)
		)
	)
	(footprint ""
		(layer "F.Cu")
		(at 13.206984 -394.447268 90)
		(property "Reference" "PC6611_1"
			(at 0 0 90)
			(layer "F.SilkS")
			(hide yes)
			(effects
				(font
					(size 1.27 1.27)
				)
			)
		)
		(property "Value" ""
			(at 0 0 90)
			(layer "F.Fab")
			(effects
				(font
					(size 1.27 1.27)
				)
			)
		)
		(duplicate_pad_numbers_are_jumpers no)
		(fp_line
			(start 0.7874 -0.4064)
			(end 0.7874 0.4064)
			(stroke
				(width 0.1524)
				(type default)
			)
			(layer "F.SilkS")
		)
		(fp_line
			(start -0.7874 -0.4064)
			(end 0.7874 -0.4064)
			(stroke
				(width 0.1524)
				(type default)
			)
			(layer "F.SilkS")
		)
		(fp_line
			(start 0.7874 0.4064)
			(end -0.7874 0.4064)
			(stroke
				(width 0.1524)
				(type default)
			)
			(layer "F.SilkS")
		)
		(fp_line
			(start -0.7874 0.4064)
			(end -0.7874 -0.4064)
			(stroke
				(width 0.1524)
				(type default)
			)
			(layer "F.SilkS")
		)
		(fp_line
			(start -0.12065 -0.305054)
			(end -0.12065 -0.2794)
			(stroke
				(width 0.1)
				(type default)
			)
			(layer "F.Fab")
		)
		(fp_line
			(start -0.67945 -0.305054)
			(end -0.12065 -0.305054)
			(stroke
				(width 0.1)
				(type default)
			)
			(layer "F.Fab")
		)
		(fp_line
			(start 0.67945 -0.3048)
			(end 0.67945 0.3048)
			(stroke
				(width 0.1)
				(type default)
			)
			(layer "F.Fab")
		)
		(fp_line
			(start 0.12065 -0.3048)
			(end 0.67945 -0.3048)
			(stroke
				(width 0.1)
				(type default)
			)
			(layer "F.Fab")
		)
		(fp_line
			(start 0.12065 -0.2794)
			(end 0.12065 -0.3048)
			(stroke
				(width 0.1)
				(type default)
			)
			(layer "F.Fab")
		)
		(fp_line
			(start -0.12065 -0.2794)
			(end 0.12065 -0.2794)
			(stroke
				(width 0.1)
				(type default)
			)
			(layer "F.Fab")
		)
		(fp_line
			(start 0.120396 0.2794)
			(end -0.12065 0.2794)
			(stroke
				(width 0.1)
				(type default)
			)
			(layer "F.Fab")
		)
		(fp_line
			(start -0.12065 0.2794)
			(end -0.12065 0.3048)
			(stroke
				(width 0.1)
				(type default)
			)
			(layer "F.Fab")
		)
		(fp_line
			(start 0.67945 0.3048)
			(end 0.120396 0.3048)
			(stroke
				(width 0.1)
				(type default)
			)
			(layer "F.Fab")
		)
		(fp_line
			(start 0.120396 0.3048)
			(end 0.120396 0.2794)
			(stroke
				(width 0.1)
				(type default)
			)
			(layer "F.Fab")
		)
		(fp_line
			(start -0.12065 0.3048)
			(end -0.67945 0.3048)
			(stroke
				(width 0.1)
				(type default)
			)
			(layer "F.Fab")
		)
		(fp_line
			(start -0.67945 0.3048)
			(end -0.67945 -0.305054)
			(stroke
				(width 0.1)
				(type default)
			)
			(layer "F.Fab")
		)
		(pad "1" smd circle
			(at -0.40005 0 90)
			(size 0 0)
			(layers "F.Cu" "F.Mask" "F.Paste")
			(net "PV09_RETIMER_CPU1_VCCS")
		)
		(pad "2" smd circle
			(at 0.40005 0 90)
			(size 0 0)
			(layers "F.Cu" "F.Mask" "F.Paste")
			(net "GND")
		)
	)
	(footprint ""
		(layer "F.Cu")
		(at 100.500434 -435.59984)
		(property "Reference" "H94"
			(at -5.619242 -4.539742 0)
			(unlocked yes)
			(layer "F.SilkS")
			(effects
				(font
					(size 0.7874 0.5842)
					(thickness 0.1524)
				)
				(justify left)
			)
		)
		(property "Value" ""
			(at 0 0 0)
			(layer "F.Fab")
			(effects
				(font
					(size 1.27 1.27)
				)
			)
		)
		(duplicate_pad_numbers_are_jumpers no)
		(pad "1" thru_hole circle
			(at 0 0)
			(size 10.0076 10.0076)
			(drill 5.6134)
			(layers "*.Cu" "*.Mask")
			(remove_unused_layers no)
			(net "GND")
			(clearance -1.9431)
		)
	)
	(footprint ""
		(layer "F.Cu")
		(at 194.945 -100.294948 -90)
		(property "Reference" "R182"
			(at 0 0 270)
			(layer "F.SilkS")
			(hide yes)
			(effects
				(font
					(size 1.27 1.27)
				)
			)
		)
		(property "Value" ""
			(at 0 0 270)
			(layer "F.Fab")
			(effects
				(font
					(size 1.27 1.27)
				)
			)
		)
		(duplicate_pad_numbers_are_jumpers no)
		(fp_line
			(start -0.7874 0.4064)
			(end -0.7874 -0.4064)
			(stroke
				(width 0.1524)
				(type default)
			)
			(layer "F.SilkS")
		)
		(fp_line
			(start 0.7874 0.4064)
			(end -0.7874 0.4064)
			(stroke
				(width 0.1524)
				(type default)
			)
			(layer "F.SilkS")
		)
		(fp_line
			(start -0.7874 -0.4064)
			(end 0.7874 -0.4064)
			(stroke
				(width 0.1524)
				(type default)
			)
			(layer "F.SilkS")
		)
		(fp_line
			(start 0.7874 -0.4064)
			(end 0.7874 0.4064)
			(stroke
				(width 0.1524)
				(type default)
			)
			(layer "F.SilkS")
		)
		(fp_line
			(start -0.67945 0.3048)
			(end -0.67945 -0.305054)
			(stroke
				(width 0.1)
				(type default)
			)
			(layer "F.Fab")
		)
		(fp_line
			(start -0.12065 0.3048)
			(end -0.67945 0.3048)
			(stroke
				(width 0.1)
				(type default)
			)
			(layer "F.Fab")
		)
		(fp_line
			(start 0.120396 0.3048)
			(end 0.120396 0.2794)
			(stroke
				(width 0.1)
				(type default)
			)
			(layer "F.Fab")
		)
		(fp_line
			(start 0.67945 0.3048)
			(end 0.120396 0.3048)
			(stroke
				(width 0.1)
				(type default)
			)
			(layer "F.Fab")
		)
		(fp_line
			(start -0.12065 0.2794)
			(end -0.12065 0.3048)
			(stroke
				(width 0.1)
				(type default)
			)
			(layer "F.Fab")
		)
		(fp_line
			(start 0.120396 0.2794)
			(end -0.12065 0.2794)
			(stroke
				(width 0.1)
				(type default)
			)
			(layer "F.Fab")
		)
		(fp_line
			(start -0.12065 -0.2794)
			(end 0.12065 -0.2794)
			(stroke
				(width 0.1)
				(type default)
			)
			(layer "F.Fab")
		)
		(fp_line
			(start 0.12065 -0.2794)
			(end 0.12065 -0.3048)
			(stroke
				(width 0.1)
				(type default)
			)
			(layer "F.Fab")
		)
		(fp_line
			(start 0.12065 -0.3048)
			(end 0.67945 -0.3048)
			(stroke
				(width 0.1)
				(type default)
			)
			(layer "F.Fab")
		)
		(fp_line
			(start 0.67945 -0.3048)
			(end 0.67945 0.3048)
			(stroke
				(width 0.1)
				(type default)
			)
			(layer "F.Fab")
		)
		(fp_line
			(start -0.67945 -0.305054)
			(end -0.12065 -0.305054)
			(stroke
				(width 0.1)
				(type default)
			)
			(layer "F.Fab")
		)
		(fp_line
			(start -0.12065 -0.305054)
			(end -0.12065 -0.2794)
			(stroke
				(width 0.1)
				(type default)
			)
			(layer "F.Fab")
		)
		(pad "1" smd circle
			(at -0.40005 0 270)
			(size 0 0)
			(layers "F.Cu" "F.Mask" "F.Paste")
			(net "FM_PRSNT_CPU0_R_N")
		)
		(pad "2" smd circle
			(at 0.40005 0 270)
			(size 0 0)
			(layers "F.Cu" "F.Mask" "F.Paste")
			(net "FM_PRSNT_CPU0_N")
		)
	)
	(footprint ""
		(layer "F.Cu")
		(at 328.514964 -151.641302)
		(property "Reference" "PR438"
			(at 0 0 0)
			(layer "F.SilkS")
			(hide yes)
			(effects
				(font
					(size 1.27 1.27)
				)
			)
		)
		(property "Value" ""
			(at 0 0 0)
			(layer "F.Fab")
			(effects
				(font
					(size 1.27 1.27)
				)
			)
		)
		(duplicate_pad_numbers_are_jumpers no)
		(fp_line
			(start -0.7874 -0.4064)
			(end 0.7874 -0.4064)
			(stroke
				(width 0.1524)
				(type default)
			)
			(layer "F.SilkS")
		)
		(fp_line
			(start -0.7874 0.4064)
			(end -0.7874 -0.4064)
			(stroke
				(width 0.1524)
				(type default)
			)
			(layer "F.SilkS")
		)
		(fp_line
			(start 0.7874 -0.4064)
			(end 0.7874 0.4064)
			(stroke
				(width 0.1524)
				(type default)
			)
			(layer "F.SilkS")
		)
		(fp_line
			(start 0.7874 0.4064)
			(end -0.7874 0.4064)
			(stroke
				(width 0.1524)
				(type default)
			)
			(layer "F.SilkS")
		)
		(fp_line
			(start -0.67945 -0.305054)
			(end -0.12065 -0.305054)
			(stroke
				(width 0.1)
				(type default)
			)
			(layer "F.Fab")
		)
		(fp_line
			(start -0.67945 0.3048)
			(end -0.67945 -0.305054)
			(stroke
				(width 0.1)
				(type default)
			)
			(layer "F.Fab")
		)
		(fp_line
			(start -0.12065 -0.305054)
			(end -0.12065 -0.2794)
			(stroke
				(width 0.1)
				(type default)
			)
			(layer "F.Fab")
		)
		(fp_line
			(start -0.12065 -0.2794)
			(end 0.12065 -0.2794)
			(stroke
				(width 0.1)
				(type default)
			)
			(layer "F.Fab")
		)
		(fp_line
			(start -0.12065 0.2794)
			(end -0.12065 0.3048)
			(stroke
				(width 0.1)
				(type default)
			)
			(layer "F.Fab")
		)
		(fp_line
			(start -0.12065 0.3048)
			(end -0.67945 0.3048)
			(stroke
				(width 0.1)
				(type default)
			)
			(layer "F.Fab")
		)
		(fp_line
			(start 0.120396 0.2794)
			(end -0.12065 0.2794)
			(stroke
				(width 0.1)
				(type default)
			)
			(layer "F.Fab")
		)
		(fp_line
			(start 0.120396 0.3048)
			(end 0.120396 0.2794)
			(stroke
				(width 0.1)
				(type default)
			)
			(layer "F.Fab")
		)
		(fp_line
			(start 0.12065 -0.3048)
			(end 0.67945 -0.3048)
			(stroke
				(width 0.1)
				(type default)
			)
			(layer "F.Fab")
		)
		(fp_line
			(start 0.12065 -0.2794)
			(end 0.12065 -0.3048)
			(stroke
				(width 0.1)
				(type default)
			)
			(layer "F.Fab")
		)
		(fp_line
			(start 0.67945 -0.3048)
			(end 0.67945 0.3048)
			(stroke
				(width 0.1)
				(type default)
			)
			(layer "F.Fab")
		)
		(fp_line
			(start 0.67945 0.3048)
			(end 0.120396 0.3048)
			(stroke
				(width 0.1)
				(type default)
			)
			(layer "F.Fab")
		)
		(pad "1" smd circle
			(at -0.40005 0)
			(size 0 0)
			(layers "F.Cu" "F.Mask" "F.Paste")
			(net "PVDD18_S5_P0_FB_RC")
		)
		(pad "2" smd circle
			(at 0.40005 0)
			(size 0 0)
			(layers "F.Cu" "F.Mask" "F.Paste")
			(net "PVDD18_S5_P0")
		)
	)
	(footprint ""
		(layer "F.Cu")
		(at 227.488242 -289.012122 180)
		(property "Reference" "C105"
			(at 0 0 180)
			(layer "F.SilkS")
			(hide yes)
			(effects
				(font
					(size 1.27 1.27)
				)
			)
		)
		(property "Value" ""
			(at 0 0 180)
			(layer "F.Fab")
			(effects
				(font
					(size 1.27 1.27)
				)
			)
		)
		(duplicate_pad_numbers_are_jumpers no)
		(fp_line
			(start 0.7874 0.4064)
			(end -0.7874 0.4064)
			(stroke
				(width 0.1524)
				(type default)
			)
			(layer "F.SilkS")
		)
		(fp_line
			(start 0.7874 -0.4064)
			(end 0.7874 0.4064)
			(stroke
				(width 0.1524)
				(type default)
			)
			(layer "F.SilkS")
		)
		(fp_line
			(start -0.7874 0.4064)
			(end -0.7874 -0.4064)
			(stroke
				(width 0.1524)
				(type default)
			)
			(layer "F.SilkS")
		)
		(fp_line
			(start -0.7874 -0.4064)
			(end 0.7874 -0.4064)
			(stroke
				(width 0.1524)
				(type default)
			)
			(layer "F.SilkS")
		)
		(fp_line
			(start 0.67945 0.3048)
			(end 0.120396 0.3048)
			(stroke
				(width 0.1)
				(type default)
			)
			(layer "F.Fab")
		)
		(fp_line
			(start 0.67945 -0.3048)
			(end 0.67945 0.3048)
			(stroke
				(width 0.1)
				(type default)
			)
			(layer "F.Fab")
		)
		(fp_line
			(start 0.12065 -0.2794)
			(end 0.12065 -0.3048)
			(stroke
				(width 0.1)
				(type default)
			)
			(layer "F.Fab")
		)
		(fp_line
			(start 0.12065 -0.3048)
			(end 0.67945 -0.3048)
			(stroke
				(width 0.1)
				(type default)
			)
			(layer "F.Fab")
		)
		(fp_line
			(start 0.120396 0.3048)
			(end 0.120396 0.2794)
			(stroke
				(width 0.1)
				(type default)
			)
			(layer "F.Fab")
		)
		(fp_line
			(start 0.120396 0.2794)
			(end -0.12065 0.2794)
			(stroke
				(width 0.1)
				(type default)
			)
			(layer "F.Fab")
		)
		(fp_line
			(start -0.12065 0.3048)
			(end -0.67945 0.3048)
			(stroke
				(width 0.1)
				(type default)
			)
			(layer "F.Fab")
		)
		(fp_line
			(start -0.12065 0.2794)
			(end -0.12065 0.3048)
			(stroke
				(width 0.1)
				(type default)
			)
			(layer "F.Fab")
		)
		(fp_line
			(start -0.12065 -0.2794)
			(end 0.12065 -0.2794)
			(stroke
				(width 0.1)
				(type default)
			)
			(layer "F.Fab")
		)
		(fp_line
			(start -0.12065 -0.305054)
			(end -0.12065 -0.2794)
			(stroke
				(width 0.1)
				(type default)
			)
			(layer "F.Fab")
		)
		(fp_line
			(start -0.67945 0.3048)
			(end -0.67945 -0.305054)
			(stroke
				(width 0.1)
				(type default)
			)
			(layer "F.Fab")
		)
		(fp_line
			(start -0.67945 -0.305054)
			(end -0.12065 -0.305054)
			(stroke
				(width 0.1)
				(type default)
			)
			(layer "F.Fab")
		)
		(pad "1" smd circle
			(at -0.40005 0 180)
			(size 0 0)
			(layers "F.Cu" "F.Mask" "F.Paste")
			(net "P1V8_RETIMER_CPU1_EN")
		)
		(pad "2" smd circle
			(at 0.40005 0 180)
			(size 0 0)
			(layers "F.Cu" "F.Mask" "F.Paste")
			(net "GND")
		)
	)
	(footprint ""
		(layer "F.Cu")
		(at 259.831586 -101.022404)
		(property "Reference" "C1512"
			(at 0 0 0)
			(layer "F.SilkS")
			(hide yes)
			(effects
				(font
					(size 1.27 1.27)
				)
			)
		)
		(property "Value" ""
			(at 0 0 0)
			(layer "F.Fab")
			(effects
				(font
					(size 1.27 1.27)
				)
			)
		)
		(duplicate_pad_numbers_are_jumpers no)
		(fp_line
			(start -0.7874 -0.4064)
			(end 0.7874 -0.4064)
			(stroke
				(width 0.1524)
				(type default)
			)
			(layer "F.SilkS")
		)
		(fp_line
			(start -0.7874 0.4064)
			(end -0.7874 -0.4064)
			(stroke
				(width 0.1524)
				(type default)
			)
			(layer "F.SilkS")
		)
		(fp_line
			(start 0.7874 -0.4064)
			(end 0.7874 0.4064)
			(stroke
				(width 0.1524)
				(type default)
			)
			(layer "F.SilkS")
		)
		(fp_line
			(start 0.7874 0.4064)
			(end -0.7874 0.4064)
			(stroke
				(width 0.1524)
				(type default)
			)
			(layer "F.SilkS")
		)
		(fp_line
			(start -0.67945 -0.305054)
			(end -0.12065 -0.305054)
			(stroke
				(width 0.1)
				(type default)
			)
			(layer "F.Fab")
		)
		(fp_line
			(start -0.67945 0.3048)
			(end -0.67945 -0.305054)
			(stroke
				(width 0.1)
				(type default)
			)
			(layer "F.Fab")
		)
		(fp_line
			(start -0.12065 -0.305054)
			(end -0.12065 -0.2794)
			(stroke
				(width 0.1)
				(type default)
			)
			(layer "F.Fab")
		)
		(fp_line
			(start -0.12065 -0.2794)
			(end 0.12065 -0.2794)
			(stroke
				(width 0.1)
				(type default)
			)
			(layer "F.Fab")
		)
		(fp_line
			(start -0.12065 0.2794)
			(end -0.12065 0.3048)
			(stroke
				(width 0.1)
				(type default)
			)
			(layer "F.Fab")
		)
		(fp_line
			(start -0.12065 0.3048)
			(end -0.67945 0.3048)
			(stroke
				(width 0.1)
				(type default)
			)
			(layer "F.Fab")
		)
		(fp_line
			(start 0.120396 0.2794)
			(end -0.12065 0.2794)
			(stroke
				(width 0.1)
				(type default)
			)
			(layer "F.Fab")
		)
		(fp_line
			(start 0.120396 0.3048)
			(end 0.120396 0.2794)
			(stroke
				(width 0.1)
				(type default)
			)
			(layer "F.Fab")
		)
		(fp_line
			(start 0.12065 -0.3048)
			(end 0.67945 -0.3048)
			(stroke
				(width 0.1)
				(type default)
			)
			(layer "F.Fab")
		)
		(fp_line
			(start 0.12065 -0.2794)
			(end 0.12065 -0.3048)
			(stroke
				(width 0.1)
				(type default)
			)
			(layer "F.Fab")
		)
		(fp_line
			(start 0.67945 -0.3048)
			(end 0.67945 0.3048)
			(stroke
				(width 0.1)
				(type default)
			)
			(layer "F.Fab")
		)
		(fp_line
			(start 0.67945 0.3048)
			(end 0.120396 0.3048)
			(stroke
				(width 0.1)
				(type default)
			)
			(layer "F.Fab")
		)
		(pad "1" smd circle
			(at -0.40005 0)
			(size 0 0)
			(layers "F.Cu" "F.Mask" "F.Paste")
			(net "JTAG_DBREQ_N")
		)
		(pad "2" smd circle
			(at 0.40005 0)
			(size 0 0)
			(layers "F.Cu" "F.Mask" "F.Paste")
			(net "GND")
		)
	)
)
